# S9S_MB_2U (Grand Teton) — schematic netlist excerpt (pin names and nets, part order shuffled) for the footprints in the layout excerpt that follows; sources: Cadence DE-HDL packaged netlist, KiCad conversion of 03242023_DA0F0TMBIJ0_F0T_Motherboard_J_brd_V01_OCP.brd

PC1279  Q_CAP  22UF 4V 20% X6S  pkg C0805  page 282 : A = PVNN_MAIN_CPU0 ; B = GND
R3235  Q_RES  100K 1% CHIP  pkg 0402LF  page 161 : A = RST_HP_OCP_V3_2_R_N ; B = GND
R2371  Q_RES  33.2 1% CHIP  pkg 0402LF  page 266 : A = SMB_VR_3V3AUX_SCL_R3 ; B = SMB_CLK_PVCCIN_CPU0

(kicad_pcb
	(version 20260206)
	(generator "pcbnew")
	(generator_version "10.0")
	(general
		(thickness 1.6)
		(legacy_teardrops no)
	)
	(paper "A4")
	(title_block
		(title "03242023_DA0F0TMBIJ0_F0T_Motherboard_J_brd_V01_OCP.brd")
		(comment 1 "Grand Teton / footprints 255-257 of 6105")
	)
	(layers
		(0 "F.Cu" signal "TOP")
		(4 "In1.Cu" signal "GND")
		(6 "In2.Cu" signal "IN1")
		(8 "In3.Cu" signal "GND1")
		(10 "In4.Cu" signal "IN2")
		(12 "In5.Cu" signal "GND2")
		(14 "In6.Cu" signal "IN3")
		(16 "In7.Cu" signal "GND3")
		(18 "In8.Cu" signal "VCC")
		(20 "In9.Cu" signal "VCC1")
		(22 "In10.Cu" signal "GND4")
		(24 "In11.Cu" signal "IN4")
		(26 "In12.Cu" signal "GND5")
		(28 "In13.Cu" signal "IN5")
		(30 "In14.Cu" signal "GND6")
		(32 "In15.Cu" signal "IN6")
		(34 "In16.Cu" signal "GND7")
		(2 "B.Cu" signal "BOTTOM")
		(9 "F.Adhes" user "F.Adhesive")
		(11 "B.Adhes" user "B.Adhesive")
		(13 "F.Paste" user "Package Geometry/Pastemask Top")
		(15 "B.Paste" user "Package Geometry/Pastemask Bottom")
		(5 "F.SilkS" user "Ref Des/Silkscreen Top")
		(7 "B.SilkS" user "Ref Des/Silkscreen Bottom")
		(1 "F.Mask" user "Board Geometry/Soldermask Top")
		(3 "B.Mask" user "Board Geometry/Soldermask Bottom")
		(17 "Dwgs.User" user "User.Drawings")
		(19 "Cmts.User" user "User.Comments")
		(21 "Eco1.User" user "User.Eco1")
		(23 "Eco2.User" user "User.Eco2")
		(25 "Edge.Cuts" user "Board Geometry/Outline")
		(27 "Margin" user)
		(31 "F.CrtYd" user "Package Geometry/Place Bound Top")
		(29 "B.CrtYd" user "Package Geometry/Place Bound Bottom")
		(35 "F.Fab" user "Ref Des/Assembly Top")
		(33 "B.Fab" user "Ref Des/Assembly Bottom")
	)
	(footprint ""
		(layer "F.Cu")
		(at 140.208 -370.423948 90)
		(property "Reference" "R2371"
			(at 0 0 90)
			(layer "F.SilkS")
			(hide yes)
			(effects
				(font
					(size 1.27 1.27)
				)
			)
		)
		(property "Value" ""
			(at 0 0 90)
			(layer "F.Fab")
			(effects
				(font
					(size 1.27 1.27)
				)
			)
		)
		(duplicate_pad_numbers_are_jumpers no)
		(fp_line
			(start 0.7874 -0.4064)
			(end 0.7874 0.4064)
			(stroke
				(width 0.1524)
				(type default)
			)
			(layer "F.SilkS")
		)
		(fp_line
			(start -0.7874 -0.4064)
			(end 0.7874 -0.4064)
			(stroke
				(width 0.1524)
				(type default)
			)
			(layer "F.SilkS")
		)
		(fp_line
			(start 0.7874 0.4064)
			(end -0.7874 0.4064)
			(stroke
				(width 0.1524)
				(type default)
			)
			(layer "F.SilkS")
		)
		(fp_line
			(start -0.7874 0.4064)
			(end -0.7874 -0.4064)
			(stroke
				(width 0.1524)
				(type default)
			)
			(layer "F.SilkS")
		)
		(fp_line
			(start -0.12065 -0.305054)
			(end -0.12065 -0.2794)
			(stroke
				(width 0.1)
				(type default)
			)
			(layer "F.Fab")
		)
		(fp_line
			(start -0.67945 -0.305054)
			(end -0.12065 -0.305054)
			(stroke
				(width 0.1)
				(type default)
			)
			(layer "F.Fab")
		)
		(fp_line
			(start 0.67945 -0.3048)
			(end 0.67945 0.3048)
			(stroke
				(width 0.1)
				(type default)
			)
			(layer "F.Fab")
		)
		(fp_line
			(start 0.12065 -0.3048)
			(end 0.67945 -0.3048)
			(stroke
				(width 0.1)
				(type default)
			)
			(layer "F.Fab")
		)
		(fp_line
			(start 0.12065 -0.2794)
			(end 0.12065 -0.3048)
			(stroke
				(width 0.1)
				(type default)
			)
			(layer "F.Fab")
		)
		(fp_line
			(start -0.12065 -0.2794)
			(end 0.12065 -0.2794)
			(stroke
				(width 0.1)
				(type default)
			)
			(layer "F.Fab")
		)
		(fp_line
			(start 0.120396 0.2794)
			(end -0.12065 0.2794)
			(stroke
				(width 0.1)
				(type default)
			)
			(layer "F.Fab")
		)
		(fp_line
			(start -0.12065 0.2794)
			(end -0.12065 0.3048)
			(stroke
				(width 0.1)
				(type default)
			)
			(layer "F.Fab")
		)
		(fp_line
			(start 0.67945 0.3048)
			(end 0.120396 0.3048)
			(stroke
				(width 0.1)
				(type default)
			)
			(layer "F.Fab")
		)
		(fp_line
			(start 0.120396 0.3048)
			(end 0.120396 0.2794)
			(stroke
				(width 0.1)
				(type default)
			)
			(layer "F.Fab")
		)
		(fp_line
			(start -0.12065 0.3048)
			(end -0.67945 0.3048)
			(stroke
				(width 0.1)
				(type default)
			)
			(layer "F.Fab")
		)
		(fp_line
			(start -0.67945 0.3048)
			(end -0.67945 -0.305054)
			(stroke
				(width 0.1)
				(type default)
			)
			(layer "F.Fab")
		)
		(pad "1" smd circle
			(at -0.40005 0 90)
			(size 0 0)
			(layers "F.Cu" "F.Mask" "F.Paste")
			(net "SMB_VR_3V3AUX_SCL_R3")
		)
		(pad "2" smd circle
			(at 0.40005 0 90)
			(size 0 0)
			(layers "F.Cu" "F.Mask" "F.Paste")
			(net "SMB_CLK_PVCCIN_CPU0")
		)
	)
	(footprint ""
		(layer "F.Cu")
		(at 446.727834 -179.862734)
		(property "Reference" "PC1279"
			(at 0 0 0)
			(layer "F.SilkS")
			(hide yes)
			(effects
				(font
					(size 1.27 1.27)
				)
			)
		)
		(property "Value" ""
			(at 0 0 0)
			(layer "F.Fab")
			(effects
				(font
					(size 1.27 1.27)
				)
			)
		)
		(duplicate_pad_numbers_are_jumpers no)
		(fp_line
			(start -1.524 -0.762)
			(end 1.524 -0.762)
			(stroke
				(width 0.1524)
				(type default)
			)
			(layer "F.SilkS")
		)
		(fp_line
			(start -1.524 0.762)
			(end -1.524 -0.762)
			(stroke
				(width 0.1524)
				(type default)
			)
			(layer "F.SilkS")
		)
		(fp_line
			(start 1.524 -0.762)
			(end 1.524 0.762)
			(stroke
				(width 0.1524)
				(type default)
			)
			(layer "F.SilkS")
		)
		(fp_line
			(start 1.524 0.762)
			(end -1.524 0.762)
			(stroke
				(width 0.1524)
				(type default)
			)
			(layer "F.SilkS")
		)
		(fp_line
			(start -1.1049 -0.724916)
			(end -1.1049 0.724916)
			(stroke
				(width 0.1)
				(type default)
			)
			(layer "F.Fab")
		)
		(fp_line
			(start -1.1049 0.724916)
			(end 1.1049 0.724916)
			(stroke
				(width 0.1)
				(type default)
			)
			(layer "F.Fab")
		)
		(fp_line
			(start 1.1049 -0.724916)
			(end -1.1049 -0.724916)
			(stroke
				(width 0.1)
				(type default)
			)
			(layer "F.Fab")
		)
		(fp_line
			(start 1.1049 0.724916)
			(end 1.1049 -0.724916)
			(stroke
				(width 0.1)
				(type default)
			)
			(layer "F.Fab")
		)
		(pad "1" smd rect
			(at -0.889 0 180)
			(size 1.016 1.27)
			(layers "F.Cu" "F.Mask" "F.Paste")
			(net "PVNN_MAIN_CPU0")
		)
		(pad "2" smd rect
			(at 0.889 0 180)
			(size 1.016 1.27)
			(layers "F.Cu" "F.Mask" "F.Paste")
			(net "GND")
		)
	)
	(footprint ""
		(layer "F.Cu")
		(at 153.21788 -112.867948 180)
		(property "Reference" "R3235"
			(at 0 0 180)
			(layer "F.SilkS")
			(hide yes)
			(effects
				(font
					(size 1.27 1.27)
				)
			)
		)
		(property "Value" ""
			(at 0 0 180)
			(layer "F.Fab")
			(effects
				(font
					(size 1.27 1.27)
				)
			)
		)
		(duplicate_pad_numbers_are_jumpers no)
		(fp_line
			(start 0.7874 0.4064)
			(end -0.7874 0.4064)
			(stroke
				(width 0.1524)
				(type default)
			)
			(layer "F.SilkS")
		)
		(fp_line
			(start 0.7874 -0.4064)
			(end 0.7874 0.4064)
			(stroke
				(width 0.1524)
				(type default)
			)
			(layer "F.SilkS")
		)
		(fp_line
			(start -0.7874 0.4064)
			(end -0.7874 -0.4064)
			(stroke
				(width 0.1524)
				(type default)
			)
			(layer "F.SilkS")
		)
		(fp_line
			(start -0.7874 -0.4064)
			(end 0.7874 -0.4064)
			(stroke
				(width 0.1524)
				(type default)
			)
			(layer "F.SilkS")
		)
		(fp_line
			(start 0.67945 0.3048)
			(end 0.120396 0.3048)
			(stroke
				(width 0.1)
				(type default)
			)
			(layer "F.Fab")
		)
		(fp_line
			(start 0.67945 -0.3048)
			(end 0.67945 0.3048)
			(stroke
				(width 0.1)
				(type default)
			)
			(layer "F.Fab")
		)
		(fp_line
			(start 0.12065 -0.2794)
			(end 0.12065 -0.3048)
			(stroke
				(width 0.1)
				(type default)
			)
			(layer "F.Fab")
		)
		(fp_line
			(start 0.12065 -0.3048)
			(end 0.67945 -0.3048)
			(stroke
				(width 0.1)
				(type default)
			)
			(layer "F.Fab")
		)
		(fp_line
			(start 0.120396 0.3048)
			(end 0.120396 0.2794)
			(stroke
				(width 0.1)
				(type default)
			)
			(layer "F.Fab")
		)
		(fp_line
			(start 0.120396 0.2794)
			(end -0.12065 0.2794)
			(stroke
				(width 0.1)
				(type default)
			)
			(layer "F.Fab")
		)
		(fp_line
			(start -0.12065 0.3048)
			(end -0.67945 0.3048)
			(stroke
				(width 0.1)
				(type default)
			)
			(layer "F.Fab")
		)
		(fp_line
			(start -0.12065 0.2794)
			(end -0.12065 0.3048)
			(stroke
				(width 0.1)
				(type default)
			)
			(layer "F.Fab")
		)
		(fp_line
			(start -0.12065 -0.2794)
			(end 0.12065 -0.2794)
			(stroke
				(width 0.1)
				(type default)
			)
			(layer "F.Fab")
		)
		(fp_line
			(start -0.12065 -0.305054)
			(end -0.12065 -0.2794)
			(stroke
				(width 0.1)
				(type default)
			)
			(layer "F.Fab")
		)
		(fp_line
			(start -0.67945 0.3048)
			(end -0.67945 -0.305054)
			(stroke
				(width 0.1)
				(type default)
			)
			(layer "F.Fab")
		)
		(fp_line
			(start -0.67945 -0.305054)
			(end -0.12065 -0.305054)
			(stroke
				(width 0.1)
				(type default)
			)
			(layer "F.Fab")
		)
		(pad "1" smd circle
			(at -0.40005 0 180)
			(size 0 0)
			(layers "F.Cu" "F.Mask" "F.Paste")
			(net "RST_HP_OCP_V3_2_R_N")
		)
		(pad "2" smd circle
			(at 0.40005 0 180)
			(size 0 0)
			(layers "F.Cu" "F.Mask" "F.Paste")
			(net "GND")
		)
	)
)
